# S9S_MB_2U (Grand Teton) — schematic netlist excerpt (pin names and nets, part order shuffled) for the footprints in the layout excerpt that follows; sources: Cadence DE-HDL packaged netlist, KiCad conversion of 03242023_DA0F0TMBIJ0_F0T_Motherboard_J_brd_V01_OCP.brd

R599  Q_RES  0 5% CHIP  pkg 0402LF  page 241 : A = I3C_SPD_DDREFGH_CPU1_BMC_R_SCL ; B = I3C_SPD_DDREFGH_CPU1_BMC_SCL
R2416  Q_RES  0 5% CHIP  pkg 0402LF  page 240 : A = SMB_1_BMC_GPU_SDA ; B = SMB_PCIE3_3V3AUX_SDA_R

(kicad_pcb
	(version 20260206)
	(generator "pcbnew")
	(generator_version "10.0")
	(general
		(thickness 1.6)
		(legacy_teardrops no)
	)
	(paper "A4")
	(title_block
		(title "03242023_DA0F0TMBIJ0_F0T_Motherboard_J_brd_V01_OCP.brd")
		(comment 1 "Grand Teton / footprints 4414-4415 of 6105")
	)
	(layers
		(0 "F.Cu" signal "TOP")
		(4 "In1.Cu" signal "GND")
		(6 "In2.Cu" signal "IN1")
		(8 "In3.Cu" signal "GND1")
		(10 "In4.Cu" signal "IN2")
		(12 "In5.Cu" signal "GND2")
		(14 "In6.Cu" signal "IN3")
		(16 "In7.Cu" signal "GND3")
		(18 "In8.Cu" signal "VCC")
		(20 "In9.Cu" signal "VCC1")
		(22 "In10.Cu" signal "GND4")
		(24 "In11.Cu" signal "IN4")
		(26 "In12.Cu" signal "GND5")
		(28 "In13.Cu" signal "IN5")
		(30 "In14.Cu" signal "GND6")
		(32 "In15.Cu" signal "IN6")
		(34 "In16.Cu" signal "GND7")
		(2 "B.Cu" signal "BOTTOM")
		(9 "F.Adhes" user "F.Adhesive")
		(11 "B.Adhes" user "B.Adhesive")
		(13 "F.Paste" user "Package Geometry/Pastemask Top")
		(15 "B.Paste" user "Package Geometry/Pastemask Bottom")
		(5 "F.SilkS" user "Ref Des/Silkscreen Top")
		(7 "B.SilkS" user "Ref Des/Silkscreen Bottom")
		(1 "F.Mask" user "Board Geometry/Soldermask Top")
		(3 "B.Mask" user "Board Geometry/Soldermask Bottom")
		(17 "Dwgs.User" user "User.Drawings")
		(19 "Cmts.User" user "User.Comments")
		(21 "Eco1.User" user "User.Eco1")
		(23 "Eco2.User" user "User.Eco2")
		(25 "Edge.Cuts" user "Board Geometry/Outline")
		(27 "Margin" user)
		(31 "F.CrtYd" user "Package Geometry/Place Bound Top")
		(29 "B.CrtYd" user "Package Geometry/Place Bound Bottom")
		(35 "F.Fab" user "Ref Des/Assembly Top")
		(33 "B.Fab" user "Ref Des/Assembly Bottom")
	)
	(footprint ""
		(layer "B.Cu")
		(at 184.059576 -13.60043 -90)
		(property "Reference" "R599"
			(at 0 0 90)
			(layer "B.SilkS")
			(hide yes)
			(effects
				(font
					(size 1.27 1.27)
				)
				(justify mirror)
			)
		)
		(property "Value" ""
			(at 0 0 90)
			(layer "B.Fab")
			(effects
				(font
					(size 1.27 1.27)
				)
				(justify mirror)
			)
		)
		(duplicate_pad_numbers_are_jumpers no)
		(fp_line
			(start -0.7874 0.4064)
			(end 0.7874 0.4064)
			(stroke
				(width 0.1524)
				(type default)
			)
			(layer "B.SilkS")
		)
		(fp_line
			(start 0.7874 0.4064)
			(end 0.7874 -0.4064)
			(stroke
				(width 0.1524)
				(type default)
			)
			(layer "B.SilkS")
		)
		(fp_line
			(start -0.7874 -0.4064)
			(end -0.7874 0.4064)
			(stroke
				(width 0.1524)
				(type default)
			)
			(layer "B.SilkS")
		)
		(fp_line
			(start 0.7874 -0.4064)
			(end -0.7874 -0.4064)
			(stroke
				(width 0.1524)
				(type default)
			)
			(layer "B.SilkS")
		)
		(fp_line
			(start -0.67945 0.3048)
			(end -0.120396 0.3048)
			(stroke
				(width 0.1)
				(type default)
			)
			(layer "B.Fab")
		)
		(fp_line
			(start -0.120396 0.3048)
			(end -0.120396 0.2794)
			(stroke
				(width 0.1)
				(type default)
			)
			(layer "B.Fab")
		)
		(fp_line
			(start 0.12065 0.3048)
			(end 0.67945 0.3048)
			(stroke
				(width 0.1)
				(type default)
			)
			(layer "B.Fab")
		)
		(fp_line
			(start 0.67945 0.3048)
			(end 0.67945 -0.305054)
			(stroke
				(width 0.1)
				(type default)
			)
			(layer "B.Fab")
		)
		(fp_line
			(start -0.120396 0.2794)
			(end 0.12065 0.2794)
			(stroke
				(width 0.1)
				(type default)
			)
			(layer "B.Fab")
		)
		(fp_line
			(start 0.12065 0.2794)
			(end 0.12065 0.3048)
			(stroke
				(width 0.1)
				(type default)
			)
			(layer "B.Fab")
		)
		(fp_line
			(start -0.12065 -0.2794)
			(end -0.12065 -0.3048)
			(stroke
				(width 0.1)
				(type default)
			)
			(layer "B.Fab")
		)
		(fp_line
			(start 0.12065 -0.2794)
			(end -0.12065 -0.2794)
			(stroke
				(width 0.1)
				(type default)
			)
			(layer "B.Fab")
		)
		(fp_line
			(start -0.67945 -0.3048)
			(end -0.67945 0.3048)
			(stroke
				(width 0.1)
				(type default)
			)
			(layer "B.Fab")
		)
		(fp_line
			(start -0.12065 -0.3048)
			(end -0.67945 -0.3048)
			(stroke
				(width 0.1)
				(type default)
			)
			(layer "B.Fab")
		)
		(fp_line
			(start 0.12065 -0.305054)
			(end 0.12065 -0.2794)
			(stroke
				(width 0.1)
				(type default)
			)
			(layer "B.Fab")
		)
		(fp_line
			(start 0.67945 -0.305054)
			(end 0.12065 -0.305054)
			(stroke
				(width 0.1)
				(type default)
			)
			(layer "B.Fab")
		)
		(pad "1" smd circle
			(at 0.40005 0 90)
			(size 0 0)
			(layers "B.Cu" "B.Mask" "B.Paste")
			(net "I3C_SPD_DDREFGH_CPU1_BMC_R_SCL")
		)
		(pad "2" smd circle
			(at -0.40005 0 90)
			(size 0 0)
			(layers "B.Cu" "B.Mask" "B.Paste")
			(net "I3C_SPD_DDREFGH_CPU1_BMC_SCL")
		)
	)
	(footprint ""
		(layer "B.Cu")
		(at 152.9969 -13.762228 90)
		(property "Reference" "R2416"
			(at 0 0 90)
			(layer "B.SilkS")
			(hide yes)
			(effects
				(font
					(size 1.27 1.27)
				)
				(justify mirror)
			)
		)
		(property "Value" ""
			(at 0 0 90)
			(layer "B.Fab")
			(effects
				(font
					(size 1.27 1.27)
				)
				(justify mirror)
			)
		)
		(duplicate_pad_numbers_are_jumpers no)
		(fp_line
			(start 0.7874 -0.4064)
			(end -0.7874 -0.4064)
			(stroke
				(width 0.1524)
				(type default)
			)
			(layer "B.SilkS")
		)
		(fp_line
			(start -0.7874 -0.4064)
			(end -0.7874 0.4064)
			(stroke
				(width 0.1524)
				(type default)
			)
			(layer "B.SilkS")
		)
		(fp_line
			(start 0.7874 0.4064)
			(end 0.7874 -0.4064)
			(stroke
				(width 0.1524)
				(type default)
			)
			(layer "B.SilkS")
		)
		(fp_line
			(start -0.7874 0.4064)
			(end 0.7874 0.4064)
			(stroke
				(width 0.1524)
				(type default)
			)
			(layer "B.SilkS")
		)
		(fp_line
			(start 0.67945 -0.305054)
			(end 0.12065 -0.305054)
			(stroke
				(width 0.1)
				(type default)
			)
			(layer "B.Fab")
		)
		(fp_line
			(start 0.12065 -0.305054)
			(end 0.12065 -0.2794)
			(stroke
				(width 0.1)
				(type default)
			)
			(layer "B.Fab")
		)
		(fp_line
			(start -0.12065 -0.3048)
			(end -0.67945 -0.3048)
			(stroke
				(width 0.1)
				(type default)
			)
			(layer "B.Fab")
		)
		(fp_line
			(start -0.67945 -0.3048)
			(end -0.67945 0.3048)
			(stroke
				(width 0.1)
				(type default)
			)
			(layer "B.Fab")
		)
		(fp_line
			(start 0.12065 -0.2794)
			(end -0.12065 -0.2794)
			(stroke
				(width 0.1)
				(type default)
			)
			(layer "B.Fab")
		)
		(fp_line
			(start -0.12065 -0.2794)
			(end -0.12065 -0.3048)
			(stroke
				(width 0.1)
				(type default)
			)
			(layer "B.Fab")
		)
		(fp_line
			(start 0.12065 0.2794)
			(end 0.12065 0.3048)
			(stroke
				(width 0.1)
				(type default)
			)
			(layer "B.Fab")
		)
		(fp_line
			(start -0.120396 0.2794)
			(end 0.12065 0.2794)
			(stroke
				(width 0.1)
				(type default)
			)
			(layer "B.Fab")
		)
		(fp_line
			(start 0.67945 0.3048)
			(end 0.67945 -0.305054)
			(stroke
				(width 0.1)
				(type default)
			)
			(layer "B.Fab")
		)
		(fp_line
			(start 0.12065 0.3048)
			(end 0.67945 0.3048)
			(stroke
				(width 0.1)
				(type default)
			)
			(layer "B.Fab")
		)
		(fp_line
			(start -0.120396 0.3048)
			(end -0.120396 0.2794)
			(stroke
				(width 0.1)
				(type default)
			)
			(layer "B.Fab")
		)
		(fp_line
			(start -0.67945 0.3048)
			(end -0.120396 0.3048)
			(stroke
				(width 0.1)
				(type default)
			)
			(layer "B.Fab")
		)
		(pad "1" smd circle
			(at 0.40005 0 270)
			(size 0 0)
			(layers "B.Cu" "B.Mask" "B.Paste")
			(net "SMB_1_BMC_GPU_SDA")
		)
		(pad "2" smd circle
			(at -0.40005 0 270)
			(size 0 0)
			(layers "B.Cu" "B.Mask" "B.Paste")
			(net "SMB_PCIE3_3V3AUX_SDA_R")
		)
	)
)
